G04*
G04 #@! TF.GenerationSoftware,Altium Limited,Altium Designer,22.4.2 (48)*
G04*
G04 Layer_Color=32768*
%FSLAX25Y25*%
%MOIN*%
G70*
G04*
G04 #@! TF.SameCoordinates,446674BB-F454-490D-8607-5140536C8ADF*
G04*
G04*
G04 #@! TF.FilePolarity,Positive*
G04*
G01*
G75*
M02*
